(kicad_pcb
	(version 20260206)
	(generator "pcbnew")
	(generator_version "10.0")
	(general
		(thickness 1.6)
		(legacy_teardrops no)
	)
	(paper "A4")
	(title_block
		(title "01162023_DA0F0TEBIF0_F0T_Expander_BD_F_brd_V02_OCP.brd")
		(comment 1 "Grand Teton / footprint 3896 of 9728 (J12), pads 78-142 of 142")
	)
	(layers
		(0 "F.Cu" signal "TOP")
		(4 "In1.Cu" signal "GND")
		(6 "In2.Cu" signal "VCC")
		(8 "In3.Cu" signal "VCC1")
		(10 "In4.Cu" signal "GND1")
		(12 "In5.Cu" signal "IN1")
		(14 "In6.Cu" signal "GND2")
		(16 "In7.Cu" signal "IN2")
		(18 "In8.Cu" signal "GND3")
		(20 "In9.Cu" signal "IN3")
		(22 "In10.Cu" signal "GND4")
		(24 "In11.Cu" signal "IN4")
		(26 "In12.Cu" signal "GND5")
		(28 "In13.Cu" signal "IN5")
		(30 "In14.Cu" signal "GND6")
		(32 "In15.Cu" signal "IN6")
		(34 "In16.Cu" signal "GND7")
		(2 "B.Cu" signal "BOTTOM")
		(9 "F.Adhes" user "F.Adhesive")
		(11 "B.Adhes" user "B.Adhesive")
		(13 "F.Paste" user "Package Geometry/Pastemask Top")
		(15 "B.Paste" user "Package Geometry/Pastemask Bottom")
		(5 "F.SilkS" user "Ref Des/Silkscreen Top")
		(7 "B.SilkS" user "Ref Des/Silkscreen Bottom")
		(1 "F.Mask" user "Board Geometry/Soldermask Top")
		(3 "B.Mask" user "Board Geometry/Soldermask Bottom")
		(17 "Dwgs.User" user "User.Drawings")
		(19 "Cmts.User" user "User.Comments")
		(21 "Eco1.User" user "User.Eco1")
		(23 "Eco2.User" user "User.Eco2")
		(25 "Edge.Cuts" user "Board Geometry/Outline")
		(27 "Margin" user)
		(31 "F.CrtYd" user "Package Geometry/Place Bound Top")
		(29 "B.CrtYd" user "Package Geometry/Place Bound Bottom")
		(35 "F.Fab" user "Ref Des/Assembly Top")
		(33 "B.Fab" user "Ref Des/Assembly Bottom")
	)
	(footprint ""
		(layer "F.Cu")
		(at 115.910106 -412.090108)
		(property "Reference" "J12"
			(at 26.161492 4.719066 90)
			(unlocked yes)
			(layer "F.SilkS")
			(effects
				(font
					(size 2.032 1.524)
					(thickness 0.1524)
				)
				(justify left)
			)
		)
		(property "Value" ""
			(at 0 0 0)
			(layer "F.Fab")
			(effects
				(font
					(size 1.27 1.27)
				)
			)
		)
		(duplicate_pad_numbers_are_jumpers no)
		(pad "N2_3" thru_hole circle
			(at 4.400042 27.29992 180)
			(size 0.906272 0.906272)
			(drill 0.499872)
			(layers "*.Cu" "*.Mask")
			(remove_unused_layers no)
			(net "GND")
			(clearance 0.0508)
			(thermal_gap 0.0508)
		)
		(pad "N2_5" thru_hole circle
			(at 8.800084 27.29992 180)
			(size 0.906272 0.906272)
			(drill 0.499872)
			(layers "*.Cu" "*.Mask")
			(remove_unused_layers no)
			(net "GND")
			(clearance 0.0508)
			(thermal_gap 0.0508)
		)
		(pad "N2_7" thru_hole circle
			(at 13.199872 27.29992 180)
			(size 0.906272 0.906272)
			(drill 0.499872)
			(layers "*.Cu" "*.Mask")
			(remove_unused_layers no)
			(net "GND")
			(clearance 0.0508)
			(thermal_gap 0.0508)
		)
		(pad "N2_9" thru_hole circle
			(at 17.599914 27.29992 180)
			(size 0.906272 0.906272)
			(drill 0.499872)
			(layers "*.Cu" "*.Mask")
			(remove_unused_layers no)
			(net "GND")
			(clearance 0.0508)
			(thermal_gap 0.0508)
		)
		(pad "N10" thru_hole circle
			(at 19.800062 27.500072 180)
			(size 0.71628 0.71628)
			(drill 0.30988)
			(layers "*.Cu" "*.Mask")
			(remove_unused_layers no)
			(net "Net_4593")
			(clearance 0.0508)
			(thermal_gap 0.0508)
		)
		(pad "O9" thru_hole circle
			(at 17.599914 28.599892 180)
			(size 0.71628 0.71628)
			(drill 0.30988)
			(layers "*.Cu" "*.Mask")
			(remove_unused_layers no)
			(net "Net_4595")
			(clearance 0.0508)
			(thermal_gap 0.0508)
		)
		(pad "O10" thru_hole circle
			(at 19.800062 28.800044 180)
			(size 0.71628 0.71628)
			(drill 0.30988)
			(layers "*.Cu" "*.Mask")
			(remove_unused_layers no)
			(net "Net_4594")
			(clearance 0.0508)
			(thermal_gap 0.0508)
		)
		(pad "P2" thru_hole circle
			(at 2.199894 30.100016 180)
			(size 0.906272 0.906272)
			(drill 0.499872)
			(layers "*.Cu" "*.Mask")
			(remove_unused_layers no)
			(net "GND")
			(clearance 0.0508)
			(thermal_gap 0.0508)
		)
		(pad "P4" thru_hole circle
			(at 6.599936 30.100016 180)
			(size 0.906272 0.906272)
			(drill 0.499872)
			(layers "*.Cu" "*.Mask")
			(remove_unused_layers no)
			(net "GND")
			(clearance 0.0508)
			(thermal_gap 0.0508)
		)
		(pad "P6" thru_hole circle
			(at 10.999978 30.100016 180)
			(size 0.906272 0.906272)
			(drill 0.499872)
			(layers "*.Cu" "*.Mask")
			(remove_unused_layers no)
			(net "GND")
			(clearance 0.0508)
			(thermal_gap 0.0508)
		)
		(pad "P8" thru_hole circle
			(at 15.40002 30.100016 180)
			(size 0.906272 0.906272)
			(drill 0.499872)
			(layers "*.Cu" "*.Mask")
			(remove_unused_layers no)
			(net "GND")
			(clearance 0.0508)
			(thermal_gap 0.0508)
		)
		(pad "P9" thru_hole circle
			(at 17.599914 29.900118 180)
			(size 0.71628 0.71628)
			(drill 0.30988)
			(layers "*.Cu" "*.Mask")
			(remove_unused_layers no)
			(net "Net_4596")
			(clearance 0.0508)
			(thermal_gap 0.0508)
		)
		(pad "P10" thru_hole circle
			(at 19.800062 30.100016 180)
			(size 0.906272 0.906272)
			(drill 0.499872)
			(layers "*.Cu" "*.Mask")
			(remove_unused_layers no)
			(net "GND")
			(clearance 0.0508)
			(thermal_gap 0.0508)
		)
		(pad "Q1" thru_hole circle
			(at 0 31.20009 180)
			(size 0.906272 0.906272)
			(drill 0.499872)
			(layers "*.Cu" "*.Mask")
			(remove_unused_layers no)
			(net "GND")
			(clearance 0.0508)
			(thermal_gap 0.0508)
		)
		(pad "Q3" thru_hole circle
			(at 4.400042 31.20009 180)
			(size 0.906272 0.906272)
			(drill 0.499872)
			(layers "*.Cu" "*.Mask")
			(remove_unused_layers no)
			(net "GND")
			(clearance 0.0508)
			(thermal_gap 0.0508)
		)
		(pad "Q5" thru_hole circle
			(at 8.800084 31.20009 180)
			(size 0.906272 0.906272)
			(drill 0.499872)
			(layers "*.Cu" "*.Mask")
			(remove_unused_layers no)
			(net "GND")
			(clearance 0.0508)
			(thermal_gap 0.0508)
		)
		(pad "Q7" thru_hole circle
			(at 13.199872 31.20009 180)
			(size 0.906272 0.906272)
			(drill 0.499872)
			(layers "*.Cu" "*.Mask")
			(remove_unused_layers no)
			(net "GND")
			(clearance 0.0508)
			(thermal_gap 0.0508)
		)
		(pad "Q9" thru_hole circle
			(at 17.599914 31.20009 180)
			(size 0.906272 0.906272)
			(drill 0.499872)
			(layers "*.Cu" "*.Mask")
			(remove_unused_layers no)
			(net "GND")
			(clearance 0.0508)
			(thermal_gap 0.0508)
		)
		(pad "Q10" thru_hole circle
			(at 19.800062 31.399988 180)
			(size 0.71628 0.71628)
			(drill 0.30988)
			(layers "*.Cu" "*.Mask")
			(remove_unused_layers no)
			(net "Net_4597")
			(clearance 0.0508)
			(thermal_gap 0.0508)
		)
		(pad "R9" thru_hole circle
			(at 17.599914 32.500062 180)
			(size 0.71628 0.71628)
			(drill 0.30988)
			(layers "*.Cu" "*.Mask")
			(remove_unused_layers no)
			(net "Net_4599")
			(clearance 0.0508)
			(thermal_gap 0.0508)
		)
		(pad "R10" thru_hole circle
			(at 19.800062 32.69996 180)
			(size 0.71628 0.71628)
			(drill 0.30988)
			(layers "*.Cu" "*.Mask")
			(remove_unused_layers no)
			(net "Net_4598")
			(clearance 0.0508)
			(thermal_gap 0.0508)
		)
		(pad "S2" thru_hole circle
			(at 2.199894 33.999932 180)
			(size 0.906272 0.906272)
			(drill 0.499872)
			(layers "*.Cu" "*.Mask")
			(remove_unused_layers no)
			(net "GND")
			(clearance 0.0508)
			(thermal_gap 0.0508)
		)
		(pad "S4" thru_hole circle
			(at 6.599936 33.999932 180)
			(size 0.906272 0.906272)
			(drill 0.499872)
			(layers "*.Cu" "*.Mask")
			(remove_unused_layers no)
			(net "GND")
			(clearance 0.0508)
			(thermal_gap 0.0508)
		)
		(pad "S6" thru_hole circle
			(at 10.999978 33.999932 180)
			(size 0.906272 0.906272)
			(drill 0.499872)
			(layers "*.Cu" "*.Mask")
			(remove_unused_layers no)
			(net "GND")
			(clearance 0.0508)
			(thermal_gap 0.0508)
		)
		(pad "S8" thru_hole circle
			(at 15.40002 33.999932 180)
			(size 0.906272 0.906272)
			(drill 0.499872)
			(layers "*.Cu" "*.Mask")
			(remove_unused_layers no)
			(net "GND")
			(clearance 0.0508)
			(thermal_gap 0.0508)
		)
		(pad "S9" thru_hole circle
			(at 17.599914 33.800034 180)
			(size 0.71628 0.71628)
			(drill 0.30988)
			(layers "*.Cu" "*.Mask")
			(remove_unused_layers no)
			(net "Net_4600")
			(clearance 0.0508)
			(thermal_gap 0.0508)
		)
		(pad "S10" thru_hole circle
			(at 19.800062 33.999932 180)
			(size 0.906272 0.906272)
			(drill 0.499872)
			(layers "*.Cu" "*.Mask")
			(remove_unused_layers no)
			(net "GND")
			(clearance 0.0508)
			(thermal_gap 0.0508)
		)
		(pad "T1" thru_hole circle
			(at 0 35.100006 180)
			(size 0.906272 0.906272)
			(drill 0.499872)
			(layers "*.Cu" "*.Mask")
			(remove_unused_layers no)
			(net "GND")
			(clearance 0.0508)
			(thermal_gap 0.0508)
		)
		(pad "T3" thru_hole circle
			(at 4.400042 35.100006 180)
			(size 0.906272 0.906272)
			(drill 0.499872)
			(layers "*.Cu" "*.Mask")
			(remove_unused_layers no)
			(net "GND")
			(clearance 0.0508)
			(thermal_gap 0.0508)
		)
		(pad "T5" thru_hole circle
			(at 8.800084 35.100006 180)
			(size 0.906272 0.906272)
			(drill 0.499872)
			(layers "*.Cu" "*.Mask")
			(remove_unused_layers no)
			(net "GND")
			(clearance 0.0508)
			(thermal_gap 0.0508)
		)
		(pad "T7" thru_hole circle
			(at 13.199872 35.100006 180)
			(size 0.906272 0.906272)
			(drill 0.499872)
			(layers "*.Cu" "*.Mask")
			(remove_unused_layers no)
			(net "GND")
			(clearance 0.0508)
			(thermal_gap 0.0508)
		)
		(pad "T9" thru_hole circle
			(at 17.599914 35.100006 180)
			(size 0.906272 0.906272)
			(drill 0.499872)
			(layers "*.Cu" "*.Mask")
			(remove_unused_layers no)
			(net "GND")
			(clearance 0.0508)
			(thermal_gap 0.0508)
		)
		(pad "T10" thru_hole circle
			(at 19.800062 35.299904 180)
			(size 0.71628 0.71628)
			(drill 0.30988)
			(layers "*.Cu" "*.Mask")
			(remove_unused_layers no)
			(net "Net_4601")
			(clearance 0.0508)
			(thermal_gap 0.0508)
		)
		(pad "U9" thru_hole circle
			(at 17.599914 36.399978 180)
			(size 0.71628 0.71628)
			(drill 0.30988)
			(layers "*.Cu" "*.Mask")
			(remove_unused_layers no)
			(net "Net_4603")
			(clearance 0.0508)
			(thermal_gap 0.0508)
		)
		(pad "U10" thru_hole circle
			(at 19.800062 36.599876 180)
			(size 0.71628 0.71628)
			(drill 0.30988)
			(layers "*.Cu" "*.Mask")
			(remove_unused_layers no)
			(net "Net_4602")
			(clearance 0.0508)
			(thermal_gap 0.0508)
		)
		(pad "V2" thru_hole circle
			(at 2.199894 37.900102 180)
			(size 0.906272 0.906272)
			(drill 0.499872)
			(layers "*.Cu" "*.Mask")
			(remove_unused_layers no)
			(net "GND")
			(clearance 0.0508)
			(thermal_gap 0.0508)
		)
		(pad "V4" thru_hole circle
			(at 6.599936 37.900102 180)
			(size 0.906272 0.906272)
			(drill 0.499872)
			(layers "*.Cu" "*.Mask")
			(remove_unused_layers no)
			(net "GND")
			(clearance 0.0508)
			(thermal_gap 0.0508)
		)
		(pad "V6" thru_hole circle
			(at 10.999978 37.900102 180)
			(size 0.906272 0.906272)
			(drill 0.499872)
			(layers "*.Cu" "*.Mask")
			(remove_unused_layers no)
			(net "GND")
			(clearance 0.0508)
			(thermal_gap 0.0508)
		)
		(pad "V8" thru_hole circle
			(at 15.40002 37.900102 180)
			(size 0.906272 0.906272)
			(drill 0.499872)
			(layers "*.Cu" "*.Mask")
			(remove_unused_layers no)
			(net "GND")
			(clearance 0.0508)
			(thermal_gap 0.0508)
		)
		(pad "V9" thru_hole circle
			(at 17.599914 37.69995 180)
			(size 0.71628 0.71628)
			(drill 0.30988)
			(layers "*.Cu" "*.Mask")
			(remove_unused_layers no)
			(net "Net_4604")
			(clearance 0.0508)
			(thermal_gap 0.0508)
		)
		(pad "V10" thru_hole circle
			(at 19.800062 37.900102 180)
			(size 0.906272 0.906272)
			(drill 0.499872)
			(layers "*.Cu" "*.Mask")
			(remove_unused_layers no)
			(net "GND")
			(clearance 0.0508)
			(thermal_gap 0.0508)
		)
		(pad "W1" thru_hole circle
			(at 0 38.999922 180)
			(size 0.906272 0.906272)
			(drill 0.499872)
			(layers "*.Cu" "*.Mask")
			(remove_unused_layers no)
			(net "GND")
			(clearance 0.0508)
			(thermal_gap 0.0508)
		)
		(pad "W3" thru_hole circle
			(at 4.400042 38.999922 180)
			(size 0.906272 0.906272)
			(drill 0.499872)
			(layers "*.Cu" "*.Mask")
			(remove_unused_layers no)
			(net "GND")
			(clearance 0.0508)
			(thermal_gap 0.0508)
		)
		(pad "W5" thru_hole circle
			(at 8.800084 38.999922 180)
			(size 0.906272 0.906272)
			(drill 0.499872)
			(layers "*.Cu" "*.Mask")
			(remove_unused_layers no)
			(net "GND")
			(clearance 0.0508)
			(thermal_gap 0.0508)
		)
		(pad "W7" thru_hole circle
			(at 13.199872 38.999922 180)
			(size 0.906272 0.906272)
			(drill 0.499872)
			(layers "*.Cu" "*.Mask")
			(remove_unused_layers no)
			(net "GND")
			(clearance 0.0508)
			(thermal_gap 0.0508)
		)
		(pad "W9" thru_hole circle
			(at 17.599914 38.999922 180)
			(size 0.906272 0.906272)
			(drill 0.499872)
			(layers "*.Cu" "*.Mask")
			(remove_unused_layers no)
			(net "GND")
			(clearance 0.0508)
			(thermal_gap 0.0508)
		)
		(pad "W10" thru_hole circle
			(at 19.800062 39.200074 180)
			(size 0.71628 0.71628)
			(drill 0.30988)
			(layers "*.Cu" "*.Mask")
			(remove_unused_layers no)
			(net "Net_4605")
			(clearance 0.0508)
			(thermal_gap 0.0508)
		)
		(pad "X9" thru_hole circle
			(at 17.599914 40.299894 180)
			(size 0.71628 0.71628)
			(drill 0.30988)
			(layers "*.Cu" "*.Mask")
			(remove_unused_layers no)
			(net "Net_4607")
			(clearance 0.0508)
			(thermal_gap 0.0508)
		)
		(pad "X10" thru_hole circle
			(at 19.800062 40.500046 180)
			(size 0.71628 0.71628)
			(drill 0.30988)
			(layers "*.Cu" "*.Mask")
			(remove_unused_layers no)
			(net "Net_4606")
			(clearance 0.0508)
			(thermal_gap 0.0508)
		)
		(pad "Y2" thru_hole circle
			(at 2.199894 41.800018 180)
			(size 0.906272 0.906272)
			(drill 0.499872)
			(layers "*.Cu" "*.Mask")
			(remove_unused_layers no)
			(net "GND")
			(clearance 0.0508)
			(thermal_gap 0.0508)
		)
		(pad "Y4" thru_hole circle
			(at 6.599936 41.800018 180)
			(size 0.906272 0.906272)
			(drill 0.499872)
			(layers "*.Cu" "*.Mask")
			(remove_unused_layers no)
			(net "GND")
			(clearance 0.0508)
			(thermal_gap 0.0508)
		)
		(pad "Y6" thru_hole circle
			(at 10.999978 41.800018 180)
			(size 0.906272 0.906272)
			(drill 0.499872)
			(layers "*.Cu" "*.Mask")
			(remove_unused_layers no)
			(net "GND")
			(clearance 0.0508)
			(thermal_gap 0.0508)
		)
		(pad "Y8" thru_hole circle
			(at 15.40002 41.800018 180)
			(size 0.906272 0.906272)
			(drill 0.499872)
			(layers "*.Cu" "*.Mask")
			(remove_unused_layers no)
			(net "GND")
			(clearance 0.0508)
			(thermal_gap 0.0508)
		)
		(pad "Y9" thru_hole circle
			(at 17.599914 41.60012 180)
			(size 0.71628 0.71628)
			(drill 0.30988)
			(layers "*.Cu" "*.Mask")
			(remove_unused_layers no)
			(net "Net_4608")
			(clearance 0.0508)
			(thermal_gap 0.0508)
		)
		(pad "Y10" thru_hole circle
			(at 19.800062 41.800018 180)
			(size 0.906272 0.906272)
			(drill 0.499872)
			(layers "*.Cu" "*.Mask")
			(remove_unused_layers no)
			(net "GND")
			(clearance 0.0508)
			(thermal_gap 0.0508)
		)
		(pad "Z1" thru_hole circle
			(at 0 42.900092 180)
			(size 0.906272 0.906272)
			(drill 0.499872)
			(layers "*.Cu" "*.Mask")
			(remove_unused_layers no)
			(net "GND")
			(clearance 0.0508)
			(thermal_gap 0.0508)
		)
		(pad "Z2" thru_hole circle
			(at 2.199894 43.09999 180)
			(size 0.71628 0.71628)
			(drill 0.30988)
			(layers "*.Cu" "*.Mask")
			(remove_unused_layers no)
			(net "GPU_FPGA_EROT_FATALERR_R_N")
			(clearance 0.0508)
			(thermal_gap 0.0508)
		)
		(pad "Z3" thru_hole circle
			(at 4.400042 42.900092 180)
			(size 0.906272 0.906272)
			(drill 0.499872)
			(layers "*.Cu" "*.Mask")
			(remove_unused_layers no)
			(net "GND")
			(clearance 0.0508)
			(thermal_gap 0.0508)
		)
		(pad "Z4" thru_hole circle
			(at 6.599936 43.09999 180)
			(size 0.71628 0.71628)
			(drill 0.30988)
			(layers "*.Cu" "*.Mask")
			(remove_unused_layers no)
			(net "GPU_3V3IO_RSVD0_FFU_R")
			(clearance 0.0508)
			(thermal_gap 0.0508)
		)
		(pad "Z5" thru_hole circle
			(at 8.800084 42.900092 180)
			(size 0.906272 0.906272)
			(drill 0.499872)
			(layers "*.Cu" "*.Mask")
			(remove_unused_layers no)
			(net "GND")
			(clearance 0.0508)
			(thermal_gap 0.0508)
		)
		(pad "Z6" thru_hole circle
			(at 10.999978 43.09999 180)
			(size 0.71628 0.71628)
			(drill 0.30988)
			(layers "*.Cu" "*.Mask")
			(remove_unused_layers no)
			(net "GPU_3V3IO_RSVD1_FFU_R")
			(clearance 0.0508)
			(thermal_gap 0.0508)
		)
		(pad "Z7" thru_hole circle
			(at 13.199872 42.900092 180)
			(size 0.906272 0.906272)
			(drill 0.499872)
			(layers "*.Cu" "*.Mask")
			(remove_unused_layers no)
			(net "GND")
			(clearance 0.0508)
			(thermal_gap 0.0508)
		)
		(pad "Z8" thru_hole circle
			(at 15.40002 43.09999 180)
			(size 0.71628 0.71628)
			(drill 0.30988)
			(layers "*.Cu" "*.Mask")
			(remove_unused_layers no)
			(net "PRSNT_SWB_B3_N")
			(clearance 0.0508)
			(thermal_gap 0.0508)
		)
		(pad "Z9" thru_hole circle
			(at 17.599914 42.900092 180)
			(size 0.906272 0.906272)
			(drill 0.499872)
			(layers "*.Cu" "*.Mask")
			(remove_unused_layers no)
			(net "GND")
			(clearance 0.0508)
			(thermal_gap 0.0508)
		)
		(pad "Z10" thru_hole circle
			(at 19.800062 43.09999 180)
			(size 0.71628 0.71628)
			(drill 0.30988)
			(layers "*.Cu" "*.Mask")
			(remove_unused_layers no)
			(net "RST_GPU_FPGA_EROT_N")
			(clearance 0.0508)
			(thermal_gap 0.0508)
		)
	)
)
